(kicad_pcb
	(version 20260206)
	(generator "pcbnew")
	(generator_version "10.0")
	(general
		(thickness 1.6)
		(legacy_teardrops no)
	)
	(paper "A4")
	(title_block
		(title "01162023_DA0F0TEBIF0_F0T_Expander_BD_F_brd_V02_OCP.brd")
		(comment 1 "Grand Teton / footprints 1742-1748 of 9728")
	)
	(layers
		(0 "F.Cu" signal "TOP")
		(4 "In1.Cu" signal "GND")
		(6 "In2.Cu" signal "VCC")
		(8 "In3.Cu" signal "VCC1")
		(10 "In4.Cu" signal "GND1")
		(12 "In5.Cu" signal "IN1")
		(14 "In6.Cu" signal "GND2")
		(16 "In7.Cu" signal "IN2")
		(18 "In8.Cu" signal "GND3")
		(20 "In9.Cu" signal "IN3")
		(22 "In10.Cu" signal "GND4")
		(24 "In11.Cu" signal "IN4")
		(26 "In12.Cu" signal "GND5")
		(28 "In13.Cu" signal "IN5")
		(30 "In14.Cu" signal "GND6")
		(32 "In15.Cu" signal "IN6")
		(34 "In16.Cu" signal "GND7")
		(2 "B.Cu" signal "BOTTOM")
		(9 "F.Adhes" user "F.Adhesive")
		(11 "B.Adhes" user "B.Adhesive")
		(13 "F.Paste" user "Package Geometry/Pastemask Top")
		(15 "B.Paste" user "Package Geometry/Pastemask Bottom")
		(5 "F.SilkS" user "Ref Des/Silkscreen Top")
		(7 "B.SilkS" user "Ref Des/Silkscreen Bottom")
		(1 "F.Mask" user "Board Geometry/Soldermask Top")
		(3 "B.Mask" user "Board Geometry/Soldermask Bottom")
		(17 "Dwgs.User" user "User.Drawings")
		(19 "Cmts.User" user "User.Comments")
		(21 "Eco1.User" user "User.Eco1")
		(23 "Eco2.User" user "User.Eco2")
		(25 "Edge.Cuts" user "Board Geometry/Outline")
		(27 "Margin" user)
		(31 "F.CrtYd" user "Package Geometry/Place Bound Top")
		(29 "B.CrtYd" user "Package Geometry/Place Bound Bottom")
		(35 "F.Fab" user "Ref Des/Assembly Top")
		(33 "B.Fab" user "Ref Des/Assembly Bottom")
	)
	(footprint ""
		(layer "F.Cu")
		(at 149.080728 -380.412498)
		(property "Reference" "R1840"
			(at 0 0 0)
			(layer "F.SilkS")
			(hide yes)
			(effects
				(font
					(size 1.27 1.27)
				)
			)
		)
		(property "Value" ""
			(at 0 0 0)
			(layer "F.Fab")
			(effects
				(font
					(size 1.27 1.27)
				)
			)
		)
		(duplicate_pad_numbers_are_jumpers no)
		(fp_line
			(start -0.7874 -0.4064)
			(end 0.7874 -0.4064)
			(stroke
				(width 0.1524)
				(type default)
			)
			(layer "F.SilkS")
		)
		(fp_line
			(start -0.7874 0.4064)
			(end -0.7874 -0.4064)
			(stroke
				(width 0.1524)
				(type default)
			)
			(layer "F.SilkS")
		)
		(fp_line
			(start 0.7874 -0.4064)
			(end 0.7874 0.4064)
			(stroke
				(width 0.1524)
				(type default)
			)
			(layer "F.SilkS")
		)
		(fp_line
			(start 0.7874 0.4064)
			(end -0.7874 0.4064)
			(stroke
				(width 0.1524)
				(type default)
			)
			(layer "F.SilkS")
		)
		(fp_line
			(start -0.67945 -0.305054)
			(end -0.12065 -0.305054)
			(stroke
				(width 0.1)
				(type default)
			)
			(layer "F.Fab")
		)
		(fp_line
			(start -0.67945 0.3048)
			(end -0.67945 -0.305054)
			(stroke
				(width 0.1)
				(type default)
			)
			(layer "F.Fab")
		)
		(fp_line
			(start -0.12065 -0.305054)
			(end -0.12065 -0.2794)
			(stroke
				(width 0.1)
				(type default)
			)
			(layer "F.Fab")
		)
		(fp_line
			(start -0.12065 -0.2794)
			(end 0.12065 -0.2794)
			(stroke
				(width 0.1)
				(type default)
			)
			(layer "F.Fab")
		)
		(fp_line
			(start -0.12065 0.2794)
			(end -0.12065 0.3048)
			(stroke
				(width 0.1)
				(type default)
			)
			(layer "F.Fab")
		)
		(fp_line
			(start -0.12065 0.3048)
			(end -0.67945 0.3048)
			(stroke
				(width 0.1)
				(type default)
			)
			(layer "F.Fab")
		)
		(fp_line
			(start 0.120396 0.2794)
			(end -0.12065 0.2794)
			(stroke
				(width 0.1)
				(type default)
			)
			(layer "F.Fab")
		)
		(fp_line
			(start 0.120396 0.3048)
			(end 0.120396 0.2794)
			(stroke
				(width 0.1)
				(type default)
			)
			(layer "F.Fab")
		)
		(fp_line
			(start 0.12065 -0.3048)
			(end 0.67945 -0.3048)
			(stroke
				(width 0.1)
				(type default)
			)
			(layer "F.Fab")
		)
		(fp_line
			(start 0.12065 -0.2794)
			(end 0.12065 -0.3048)
			(stroke
				(width 0.1)
				(type default)
			)
			(layer "F.Fab")
		)
		(fp_line
			(start 0.67945 -0.3048)
			(end 0.67945 0.3048)
			(stroke
				(width 0.1)
				(type default)
			)
			(layer "F.Fab")
		)
		(fp_line
			(start 0.67945 0.3048)
			(end 0.120396 0.3048)
			(stroke
				(width 0.1)
				(type default)
			)
			(layer "F.Fab")
		)
		(pad "1" smd circle
			(at -0.40005 0)
			(size 0 0)
			(layers "F.Cu" "F.Mask" "F.Paste")
			(net "GPU_3V3IO_RSVD0_FFU_R")
		)
		(pad "2" smd circle
			(at 0.40005 0)
			(size 0 0)
			(layers "F.Cu" "F.Mask" "F.Paste")
			(net "GPU_3V3IO_RSVD0_FFU")
		)
	)
	(footprint ""
		(layer "F.Cu")
		(at 367.798604 -66.32194 -90)
		(property "Reference" "PC882"
			(at 0 0 270)
			(layer "F.SilkS")
			(hide yes)
			(effects
				(font
					(size 1.27 1.27)
				)
			)
		)
		(property "Value" ""
			(at 0 0 270)
			(layer "F.Fab")
			(effects
				(font
					(size 1.27 1.27)
				)
			)
		)
		(duplicate_pad_numbers_are_jumpers no)
		(fp_line
			(start -0.7874 0.4064)
			(end -0.7874 -0.4064)
			(stroke
				(width 0.1524)
				(type default)
			)
			(layer "F.SilkS")
		)
		(fp_line
			(start 0.7874 0.4064)
			(end -0.7874 0.4064)
			(stroke
				(width 0.1524)
				(type default)
			)
			(layer "F.SilkS")
		)
		(fp_line
			(start -0.7874 -0.4064)
			(end 0.7874 -0.4064)
			(stroke
				(width 0.1524)
				(type default)
			)
			(layer "F.SilkS")
		)
		(fp_line
			(start 0.7874 -0.4064)
			(end 0.7874 0.4064)
			(stroke
				(width 0.1524)
				(type default)
			)
			(layer "F.SilkS")
		)
		(fp_line
			(start -0.67945 0.3048)
			(end -0.67945 -0.305054)
			(stroke
				(width 0.1)
				(type default)
			)
			(layer "F.Fab")
		)
		(fp_line
			(start -0.12065 0.3048)
			(end -0.67945 0.3048)
			(stroke
				(width 0.1)
				(type default)
			)
			(layer "F.Fab")
		)
		(fp_line
			(start 0.120396 0.3048)
			(end 0.120396 0.2794)
			(stroke
				(width 0.1)
				(type default)
			)
			(layer "F.Fab")
		)
		(fp_line
			(start 0.67945 0.3048)
			(end 0.120396 0.3048)
			(stroke
				(width 0.1)
				(type default)
			)
			(layer "F.Fab")
		)
		(fp_line
			(start -0.12065 0.2794)
			(end -0.12065 0.3048)
			(stroke
				(width 0.1)
				(type default)
			)
			(layer "F.Fab")
		)
		(fp_line
			(start 0.120396 0.2794)
			(end -0.12065 0.2794)
			(stroke
				(width 0.1)
				(type default)
			)
			(layer "F.Fab")
		)
		(fp_line
			(start -0.12065 -0.2794)
			(end 0.12065 -0.2794)
			(stroke
				(width 0.1)
				(type default)
			)
			(layer "F.Fab")
		)
		(fp_line
			(start 0.12065 -0.2794)
			(end 0.12065 -0.3048)
			(stroke
				(width 0.1)
				(type default)
			)
			(layer "F.Fab")
		)
		(fp_line
			(start 0.12065 -0.3048)
			(end 0.67945 -0.3048)
			(stroke
				(width 0.1)
				(type default)
			)
			(layer "F.Fab")
		)
		(fp_line
			(start 0.67945 -0.3048)
			(end 0.67945 0.3048)
			(stroke
				(width 0.1)
				(type default)
			)
			(layer "F.Fab")
		)
		(fp_line
			(start -0.67945 -0.305054)
			(end -0.12065 -0.305054)
			(stroke
				(width 0.1)
				(type default)
			)
			(layer "F.Fab")
		)
		(fp_line
			(start -0.12065 -0.305054)
			(end -0.12065 -0.2794)
			(stroke
				(width 0.1)
				(type default)
			)
			(layer "F.Fab")
		)
		(pad "1" smd circle
			(at -0.40005 0 270)
			(size 0 0)
			(layers "F.Cu" "F.Mask" "F.Paste")
			(net "P12V_SSD12_CO_GATE")
		)
		(pad "2" smd circle
			(at 0.40005 0 270)
			(size 0 0)
			(layers "F.Cu" "F.Mask" "F.Paste")
			(net "GND")
		)
	)
	(footprint ""
		(layer "F.Cu")
		(at 484.108506 -524.787368 180)
		(property "Reference" "J34_OTH"
			(at -3.2385 -1.402334 0)
			(unlocked yes)
			(layer "B.SilkS")
			(effects
				(font
					(size 0.7874 0.5842)
					(thickness 0.1524)
				)
				(justify mirror)
			)
		)
		(property "Value" ""
			(at 0 0 180)
			(layer "F.Fab")
			(effects
				(font
					(size 1.27 1.27)
				)
			)
		)
		(duplicate_pad_numbers_are_jumpers no)
		(pad "1" thru_hole circle
			(at 0 0 180)
			(size 0.4572 0.4572)
			(drill 0.2032)
			(layers "*.Cu" "*.Mask")
			(remove_unused_layers no)
			(net "Net_9102")
			(clearance 0.127)
			(thermal_gap 0.127)
			(padstack
				(mode front_inner_back)
				(layer "Inner"
					(shape circle)
					(size 0.4572 0.4572)
					(clearance 0.127)
				)
				(layer "B.Cu"
					(shape circle)
					(size 0.508 0.508)
					(clearance 0.1016)
				)
			)
		)
	)
	(footprint ""
		(layer "F.Cu")
		(at 338.074 -184.023 180)
		(property "Reference" "R4761"
			(at 0 0 180)
			(layer "F.SilkS")
			(hide yes)
			(effects
				(font
					(size 1.27 1.27)
				)
			)
		)
		(property "Value" ""
			(at 0 0 180)
			(layer "F.Fab")
			(effects
				(font
					(size 1.27 1.27)
				)
			)
		)
		(duplicate_pad_numbers_are_jumpers no)
		(fp_line
			(start 0.7874 0.4064)
			(end -0.7874 0.4064)
			(stroke
				(width 0.1524)
				(type default)
			)
			(layer "F.SilkS")
		)
		(fp_line
			(start 0.7874 -0.4064)
			(end 0.7874 0.4064)
			(stroke
				(width 0.1524)
				(type default)
			)
			(layer "F.SilkS")
		)
		(fp_line
			(start -0.7874 0.4064)
			(end -0.7874 -0.4064)
			(stroke
				(width 0.1524)
				(type default)
			)
			(layer "F.SilkS")
		)
		(fp_line
			(start -0.7874 -0.4064)
			(end 0.7874 -0.4064)
			(stroke
				(width 0.1524)
				(type default)
			)
			(layer "F.SilkS")
		)
		(fp_line
			(start 0.67945 0.3048)
			(end 0.120396 0.3048)
			(stroke
				(width 0.1)
				(type default)
			)
			(layer "F.Fab")
		)
		(fp_line
			(start 0.67945 -0.3048)
			(end 0.67945 0.3048)
			(stroke
				(width 0.1)
				(type default)
			)
			(layer "F.Fab")
		)
		(fp_line
			(start 0.12065 -0.2794)
			(end 0.12065 -0.3048)
			(stroke
				(width 0.1)
				(type default)
			)
			(layer "F.Fab")
		)
		(fp_line
			(start 0.12065 -0.3048)
			(end 0.67945 -0.3048)
			(stroke
				(width 0.1)
				(type default)
			)
			(layer "F.Fab")
		)
		(fp_line
			(start 0.120396 0.3048)
			(end 0.120396 0.2794)
			(stroke
				(width 0.1)
				(type default)
			)
			(layer "F.Fab")
		)
		(fp_line
			(start 0.120396 0.2794)
			(end -0.12065 0.2794)
			(stroke
				(width 0.1)
				(type default)
			)
			(layer "F.Fab")
		)
		(fp_line
			(start -0.12065 0.3048)
			(end -0.67945 0.3048)
			(stroke
				(width 0.1)
				(type default)
			)
			(layer "F.Fab")
		)
		(fp_line
			(start -0.12065 0.2794)
			(end -0.12065 0.3048)
			(stroke
				(width 0.1)
				(type default)
			)
			(layer "F.Fab")
		)
		(fp_line
			(start -0.12065 -0.2794)
			(end 0.12065 -0.2794)
			(stroke
				(width 0.1)
				(type default)
			)
			(layer "F.Fab")
		)
		(fp_line
			(start -0.12065 -0.305054)
			(end -0.12065 -0.2794)
			(stroke
				(width 0.1)
				(type default)
			)
			(layer "F.Fab")
		)
		(fp_line
			(start -0.67945 0.3048)
			(end -0.67945 -0.305054)
			(stroke
				(width 0.1)
				(type default)
			)
			(layer "F.Fab")
		)
		(fp_line
			(start -0.67945 -0.305054)
			(end -0.12065 -0.305054)
			(stroke
				(width 0.1)
				(type default)
			)
			(layer "F.Fab")
		)
		(pad "1" smd circle
			(at -0.40005 0 180)
			(size 0 0)
			(layers "F.Cu" "F.Mask" "F.Paste")
			(net "GND")
		)
		(pad "2" smd circle
			(at 0.40005 0 180)
			(size 0 0)
			(layers "F.Cu" "F.Mask" "F.Paste")
			(net "PCA9555_0_PEX2_A2")
		)
	)
	(footprint ""
		(layer "F.Cu")
		(at 379.694186 -29.507688 -90)
		(property "Reference" "PC966"
			(at 0 0 270)
			(layer "F.SilkS")
			(hide yes)
			(effects
				(font
					(size 1.27 1.27)
				)
			)
		)
		(property "Value" ""
			(at 0 0 270)
			(layer "F.Fab")
			(effects
				(font
					(size 1.27 1.27)
				)
			)
		)
		(duplicate_pad_numbers_are_jumpers no)
		(fp_line
			(start -1.524 0.762)
			(end -1.524 -0.762)
			(stroke
				(width 0.1524)
				(type default)
			)
			(layer "F.SilkS")
		)
		(fp_line
			(start 1.524 0.762)
			(end -1.524 0.762)
			(stroke
				(width 0.1524)
				(type default)
			)
			(layer "F.SilkS")
		)
		(fp_line
			(start -1.524 -0.762)
			(end 1.524 -0.762)
			(stroke
				(width 0.1524)
				(type default)
			)
			(layer "F.SilkS")
		)
		(fp_line
			(start 1.524 -0.762)
			(end 1.524 0.762)
			(stroke
				(width 0.1524)
				(type default)
			)
			(layer "F.SilkS")
		)
		(fp_line
			(start -1.1049 0.724916)
			(end 1.1049 0.724916)
			(stroke
				(width 0.1)
				(type default)
			)
			(layer "F.Fab")
		)
		(fp_line
			(start 1.1049 0.724916)
			(end 1.1049 -0.724916)
			(stroke
				(width 0.1)
				(type default)
			)
			(layer "F.Fab")
		)
		(fp_line
			(start -1.1049 -0.724916)
			(end -1.1049 0.724916)
			(stroke
				(width 0.1)
				(type default)
			)
			(layer "F.Fab")
		)
		(fp_line
			(start 1.1049 -0.724916)
			(end -1.1049 -0.724916)
			(stroke
				(width 0.1)
				(type default)
			)
			(layer "F.Fab")
		)
		(pad "1" smd rect
			(at -0.889 0 90)
			(size 1.016 1.27)
			(layers "F.Cu" "F.Mask" "F.Paste")
			(net "P3V3_SSD13")
		)
		(pad "2" smd rect
			(at 0.889 0 90)
			(size 1.016 1.27)
			(layers "F.Cu" "F.Mask" "F.Paste")
			(net "GND")
		)
	)
	(footprint ""
		(layer "F.Cu")
		(at 400.567906 -51.019456)
		(property "Reference" "PC423"
			(at 0 0 0)
			(layer "F.SilkS")
			(hide yes)
			(effects
				(font
					(size 1.27 1.27)
				)
			)
		)
		(property "Value" ""
			(at 0 0 0)
			(layer "F.Fab")
			(effects
				(font
					(size 1.27 1.27)
				)
			)
		)
		(duplicate_pad_numbers_are_jumpers no)
		(fp_line
			(start -0.7874 -0.4064)
			(end 0.7874 -0.4064)
			(stroke
				(width 0.1524)
				(type default)
			)
			(layer "F.SilkS")
		)
		(fp_line
			(start -0.7874 0.4064)
			(end -0.7874 -0.4064)
			(stroke
				(width 0.1524)
				(type default)
			)
			(layer "F.SilkS")
		)
		(fp_line
			(start 0.7874 -0.4064)
			(end 0.7874 0.4064)
			(stroke
				(width 0.1524)
				(type default)
			)
			(layer "F.SilkS")
		)
		(fp_line
			(start 0.7874 0.4064)
			(end -0.7874 0.4064)
			(stroke
				(width 0.1524)
				(type default)
			)
			(layer "F.SilkS")
		)
		(fp_line
			(start -0.67945 -0.305054)
			(end -0.12065 -0.305054)
			(stroke
				(width 0.1)
				(type default)
			)
			(layer "F.Fab")
		)
		(fp_line
			(start -0.67945 0.3048)
			(end -0.67945 -0.305054)
			(stroke
				(width 0.1)
				(type default)
			)
			(layer "F.Fab")
		)
		(fp_line
			(start -0.12065 -0.305054)
			(end -0.12065 -0.2794)
			(stroke
				(width 0.1)
				(type default)
			)
			(layer "F.Fab")
		)
		(fp_line
			(start -0.12065 -0.2794)
			(end 0.12065 -0.2794)
			(stroke
				(width 0.1)
				(type default)
			)
			(layer "F.Fab")
		)
		(fp_line
			(start -0.12065 0.2794)
			(end -0.12065 0.3048)
			(stroke
				(width 0.1)
				(type default)
			)
			(layer "F.Fab")
		)
		(fp_line
			(start -0.12065 0.3048)
			(end -0.67945 0.3048)
			(stroke
				(width 0.1)
				(type default)
			)
			(layer "F.Fab")
		)
		(fp_line
			(start 0.120396 0.2794)
			(end -0.12065 0.2794)
			(stroke
				(width 0.1)
				(type default)
			)
			(layer "F.Fab")
		)
		(fp_line
			(start 0.120396 0.3048)
			(end 0.120396 0.2794)
			(stroke
				(width 0.1)
				(type default)
			)
			(layer "F.Fab")
		)
		(fp_line
			(start 0.12065 -0.3048)
			(end 0.67945 -0.3048)
			(stroke
				(width 0.1)
				(type default)
			)
			(layer "F.Fab")
		)
		(fp_line
			(start 0.12065 -0.2794)
			(end 0.12065 -0.3048)
			(stroke
				(width 0.1)
				(type default)
			)
			(layer "F.Fab")
		)
		(fp_line
			(start 0.67945 -0.3048)
			(end 0.67945 0.3048)
			(stroke
				(width 0.1)
				(type default)
			)
			(layer "F.Fab")
		)
		(fp_line
			(start 0.67945 0.3048)
			(end 0.120396 0.3048)
			(stroke
				(width 0.1)
				(type default)
			)
			(layer "F.Fab")
		)
		(pad "1" smd circle
			(at -0.40005 0)
			(size 0 0)
			(layers "F.Cu" "F.Mask" "F.Paste")
			(net "P12V_SSD13_SS")
		)
		(pad "2" smd circle
			(at 0.40005 0)
			(size 0 0)
			(layers "F.Cu" "F.Mask" "F.Paste")
			(net "GND")
		)
	)
	(footprint ""
		(layer "F.Cu")
		(at 33.854136 -307.415438 45)
		(property "Reference" "R1186"
			(at 0 0 45)
			(layer "F.SilkS")
			(hide yes)
			(effects
				(font
					(size 1.27 1.27)
				)
			)
		)
		(property "Value" ""
			(at 0 0 45)
			(layer "F.Fab")
			(effects
				(font
					(size 1.27 1.27)
				)
			)
		)
		(duplicate_pad_numbers_are_jumpers no)
		(fp_line
			(start -0.787389 -0.406267)
			(end 0.787389 -0.406267)
			(stroke
				(width 0.1524)
				(type default)
			)
			(layer "F.SilkS")
		)
		(fp_line
			(start -0.787389 0.406267)
			(end -0.787389 -0.406267)
			(stroke
				(width 0.1524)
				(type default)
			)
			(layer "F.SilkS")
		)
		(fp_line
			(start 0.787389 -0.406267)
			(end 0.787389 0.406267)
			(stroke
				(width 0.1524)
				(type default)
			)
			(layer "F.SilkS")
		)
		(fp_line
			(start 0.787389 0.406267)
			(end -0.787389 0.406267)
			(stroke
				(width 0.1524)
				(type default)
			)
			(layer "F.SilkS")
		)
		(fp_line
			(start -0.679446 -0.305149)
			(end -0.120695 -0.304969)
			(stroke
				(width 0.1)
				(type default)
			)
			(layer "F.Fab")
		)
		(fp_line
			(start -0.120695 -0.304969)
			(end -0.120695 -0.279466)
			(stroke
				(width 0.1)
				(type default)
			)
			(layer "F.Fab")
		)
		(fp_line
			(start -0.120695 -0.279466)
			(end 0.120695 -0.279466)
			(stroke
				(width 0.1)
				(type default)
			)
			(layer "F.Fab")
		)
		(fp_line
			(start -0.679446 0.30479)
			(end -0.679446 -0.305149)
			(stroke
				(width 0.1)
				(type default)
			)
			(layer "F.Fab")
		)
		(fp_line
			(start 0.120515 -0.30479)
			(end 0.679446 -0.30479)
			(stroke
				(width 0.1)
				(type default)
			)
			(layer "F.Fab")
		)
		(fp_line
			(start 0.120695 -0.279466)
			(end 0.120515 -0.30479)
			(stroke
				(width 0.1)
				(type default)
			)
			(layer "F.Fab")
		)
		(fp_line
			(start -0.120695 0.279466)
			(end -0.120515 0.30479)
			(stroke
				(width 0.1)
				(type default)
			)
			(layer "F.Fab")
		)
		(fp_line
			(start -0.120515 0.30479)
			(end -0.679446 0.30479)
			(stroke
				(width 0.1)
				(type default)
			)
			(layer "F.Fab")
		)
		(fp_line
			(start 0.679446 -0.30479)
			(end 0.679446 0.30479)
			(stroke
				(width 0.1)
				(type default)
			)
			(layer "F.Fab")
		)
		(fp_line
			(start 0.120335 0.279466)
			(end -0.120695 0.279466)
			(stroke
				(width 0.1)
				(type default)
			)
			(layer "F.Fab")
		)
		(fp_line
			(start 0.120515 0.30479)
			(end 0.120335 0.279466)
			(stroke
				(width 0.1)
				(type default)
			)
			(layer "F.Fab")
		)
		(fp_line
			(start 0.679446 0.30479)
			(end 0.120515 0.30479)
			(stroke
				(width 0.1)
				(type default)
			)
			(layer "F.Fab")
		)
		(pad "1" smd circle
			(at -0.40005 0 45)
			(size 0 0)
			(layers "F.Cu" "F.Mask" "F.Paste")
			(net "GND")
		)
		(pad "2" smd circle
			(at 0.40005 0 45)
			(size 0 0)
			(layers "F.Cu" "F.Mask" "F.Paste")
			(net "PEX0_DBG_MODE1")
		)
	)
)
